(kicad_pcb
	(version 20240108)
	(generator "pcbnew")
	(generator_version "8.0")
	(general
		(thickness 1.62)
		(legacy_teardrops no)
	)
	(paper "A4")
	(title_block
		(title "Jetson Orin Baseboard")
		(date "2025-03-12")
		(rev "1.3.4")
		(company "Antmicro Ltd")
		(comment 1 "www.antmicro.com")
		(comment 9 "footprints 524-527 of 677")
	)
	(layers
		(0 "F.Cu" signal)
		(1 "In1.Cu" signal)
		(2 "In2.Cu" signal)
		(3 "In3.Cu" signal)
		(4 "In4.Cu" jumper)
		(5 "In5.Cu" signal)
		(6 "In6.Cu" signal)
		(31 "B.Cu" signal)
		(32 "B.Adhes" user "B.Adhesive")
		(33 "F.Adhes" user "F.Adhesive")
		(34 "B.Paste" user)
		(35 "F.Paste" user)
		(36 "B.SilkS" user "B.Silkscreen")
		(37 "F.SilkS" user "F.Silkscreen")
		(38 "B.Mask" user)
		(39 "F.Mask" user)
		(40 "Dwgs.User" user "User.Drawings")
		(41 "Cmts.User" user "User.Comments")
		(42 "Eco1.User" user "User.Eco1")
		(43 "Eco2.User" user "User.Eco2")
		(44 "Edge.Cuts" user)
		(45 "Margin" user)
		(46 "B.CrtYd" user "B.Courtyard")
		(47 "F.CrtYd" user "F.Courtyard")
		(48 "B.Fab" user)
		(49 "F.Fab" user)
	)
	(footprint "antmicro-footprints:R_Array_4x0201_Panasonic_EXB18V"
		(layer "B.Cu")
		(at 61.15 104.9 -90)
		(property "Reference" "R33"
			(at 1.32 0.64 90)
			(layer "B.SilkS")
			(effects
				(font
					(size 0.7 0.7)
					(thickness 0.15)
				)
				(justify right bottom mirror)
			)
		)
		(property "Value" "R_4x0R_0201_array"
			(at -1.1 -1.8 90)
			(layer "B.Fab")
			(effects
				(font
					(size 0.7 0.7)
					(thickness 0.15)
				)
				(justify left bottom mirror)
			)
		)
		(property "Footprint" "antmicro-footprints:R_Array_4x0201_Panasonic_EXB18V"
			(at 0 0 -90)
			(layer "F.Fab")
			(hide yes)
			(effects
				(font
					(size 1.27 1.27)
					(thickness 0.15)
				)
			)
		)
		(property "Datasheet" "http://industrial.panasonic.com/cdbs/www-data/pdf/AOC0000/AOC0000C14.pdf"
			(at 0 0 -90)
			(layer "F.Fab")
			(hide yes)
			(effects
				(font
					(size 1.27 1.27)
					(thickness 0.15)
				)
			)
		)
		(property "Author" "Antmicro"
			(at -43.75 166.05 0)
			(layer "B.Fab")
			(hide yes)
			(effects
				(font
					(size 1 1)
					(thickness 0.15)
				)
				(justify mirror)
			)
		)
		(property "License" "Apache-2.0"
			(at -43.75 166.05 0)
			(layer "B.Fab")
			(hide yes)
			(effects
				(font
					(size 1 1)
					(thickness 0.15)
				)
				(justify mirror)
			)
		)
		(property "MPN" "EXB-18VR000X"
			(at -43.75 166.05 0)
			(layer "B.Fab")
			(hide yes)
			(effects
				(font
					(size 1 1)
					(thickness 0.15)
				)
				(justify mirror)
			)
		)
		(property "Manufacturer" "Panasonic"
			(at -43.75 166.05 0)
			(layer "B.Fab")
			(hide yes)
			(effects
				(font
					(size 1 1)
					(thickness 0.15)
				)
				(justify mirror)
			)
		)
		(property "Val" "4x0R_0201"
			(at -43.75 166.05 0)
			(layer "B.Fab")
			(hide yes)
			(effects
				(font
					(size 1 1)
					(thickness 0.15)
				)
				(justify mirror)
			)
		)
		(sheetname "USB Debug, DP")
		(sheetfile "usb.kicad_sch")
		(attr smd)
		(fp_line
			(start -0.8 -0.45)
			(end -0.8 0.45)
			(stroke
				(width 0.12)
				(type solid)
			)
			(layer "B.SilkS")
		)
		(fp_line
			(start 0.8 -0.45)
			(end 0.8 0.45)
			(stroke
				(width 0.12)
				(type solid)
			)
			(layer "B.SilkS")
		)
		(fp_rect
			(start -0.898 0.66)
			(end 0.898 -0.65)
			(stroke
				(width 0.05)
				(type solid)
			)
			(fill none)
			(layer "B.CrtYd")
		)
		(fp_text user "${REFERENCE}"
			(at -1.051 -3.2 90)
			(layer "B.Fab")
			(hide yes)
			(effects
				(font
					(size 0.7 0.7)
					(thickness 0.15)
				)
				(justify left bottom mirror)
			)
		)
		(fp_text user "Author: Antmicro"
			(at -1.051 -4.599 90)
			(layer "B.Fab")
			(hide yes)
			(effects
				(font
					(size 0.7 0.7)
					(thickness 0.15)
				)
				(justify left bottom mirror)
			)
		)
		(fp_text user "License: Apache-2.0"
			(at -1.051 -6 90)
			(layer "B.Fab")
			(hide yes)
			(effects
				(font
					(size 0.7 0.7)
					(thickness 0.15)
				)
				(justify left bottom mirror)
			)
		)
		(pad "1" smd roundrect
			(at -0.6 -0.298 270)
			(size 0.2 0.4)
			(layers "B.Cu" "B.Paste" "B.Mask")
			(roundrect_rratio 0.25)
			(net 294 "/USB Debug, DP/PDC_CTL1")
			(pinfunction "R1.1")
			(pintype "passive")
		)
		(pad "2" smd roundrect
			(at -0.202 -0.298 270)
			(size 0.2 0.4)
			(layers "B.Cu" "B.Paste" "B.Mask")
			(roundrect_rratio 0.25)
			(net 298 "/USB Debug, DP/PDC_CTL0")
			(pinfunction "R2.1")
			(pintype "passive")
		)
		(pad "3" smd roundrect
			(at 0.2 -0.298 270)
			(size 0.2 0.4)
			(layers "B.Cu" "B.Paste" "B.Mask")
			(roundrect_rratio 0.25)
			(net 296 "/USB Debug, DP/PDC_FLIP")
			(pinfunction "R3.1")
			(pintype "passive")
		)
		(pad "4" smd roundrect
			(at 0.598 -0.298 270)
			(size 0.2 0.4)
			(layers "B.Cu" "B.Paste" "B.Mask")
			(roundrect_rratio 0.25)
			(net 633 "unconnected-(R33-R4.1-Pad4)")
			(pinfunction "R4.1")
			(pintype "passive+no_connect")
		)
		(pad "5" smd roundrect
			(at 0.598 0.3 270)
			(size 0.2 0.4)
			(layers "B.Cu" "B.Paste" "B.Mask")
			(roundrect_rratio 0.25)
			(net 634 "unconnected-(R33-R4.2-Pad5)")
			(pinfunction "R4.2")
			(pintype "passive+no_connect")
		)
		(pad "6" smd roundrect
			(at 0.2 0.3 270)
			(size 0.2 0.4)
			(layers "B.Cu" "B.Paste" "B.Mask")
			(roundrect_rratio 0.25)
			(net 293 "/USB Debug, DP/USBC0_FLIP")
			(pinfunction "R3.2")
			(pintype "passive")
		)
		(pad "7" smd roundrect
			(at -0.202 0.3 270)
			(size 0.2 0.4)
			(layers "B.Cu" "B.Paste" "B.Mask")
			(roundrect_rratio 0.25)
			(net 295 "/USB Debug, DP/USBC0_CTL0")
			(pinfunction "R2.2")
			(pintype "passive")
		)
		(pad "8" smd roundrect
			(at -0.6 0.3 270)
			(size 0.2 0.4)
			(layers "B.Cu" "B.Paste" "B.Mask")
			(roundrect_rratio 0.25)
			(net 297 "/USB Debug, DP/USBC0_CTL1")
			(pinfunction "R1.2")
			(pintype "passive")
		)
	)
	(footprint "antmicro-footprints:C_0402_1005Metric"
		(layer "B.Cu")
		(at 95.55 94.9)
		(descr "Capacitor SMD 0402")
		(tags "capacitor SMD 0402")
		(property "Reference" "C92"
			(at 5.21 0.62 180)
			(layer "B.SilkS")
			(effects
				(font
					(size 0.7 0.7)
					(thickness 0.15)
				)
				(justify left bottom mirror)
			)
		)
		(property "Value" "C_100n_0402"
			(at 0 -1.4 180)
			(layer "B.Fab")
			(effects
				(font
					(size 0.7 0.7)
					(thickness 0.15)
				)
				(justify left bottom mirror)
			)
		)
		(property "Footprint" "antmicro-footprints:C_0402_1005Metric"
			(at 0 0 0)
			(layer "F.Fab")
			(hide yes)
			(effects
				(font
					(size 1.27 1.27)
					(thickness 0.15)
				)
			)
		)
		(property "Datasheet" "https://www.murata.com/products/productdetail?partno=GRM155R61H104KE14%23"
			(at 0 0 0)
			(layer "F.Fab")
			(hide yes)
			(effects
				(font
					(size 1.27 1.27)
					(thickness 0.15)
				)
			)
		)
		(property "Author" "Antmicro"
			(at 0 0 0)
			(layer "B.Fab")
			(hide yes)
			(effects
				(font
					(size 1 1)
					(thickness 0.15)
				)
				(justify mirror)
			)
		)
		(property "Dielectric" "X5R"
			(at 0 0 0)
			(layer "B.Fab")
			(hide yes)
			(effects
				(font
					(size 1 1)
					(thickness 0.15)
				)
				(justify mirror)
			)
		)
		(property "License" "Apache-2.0"
			(at 0 0 0)
			(layer "B.Fab")
			(hide yes)
			(effects
				(font
					(size 1 1)
					(thickness 0.15)
				)
				(justify mirror)
			)
		)
		(property "MPN" "GRM155R61H104KE14D"
			(at 0 0 0)
			(layer "B.Fab")
			(hide yes)
			(effects
				(font
					(size 1 1)
					(thickness 0.15)
				)
				(justify mirror)
			)
		)
		(property "Manufacturer" "Murata"
			(at 0 0 0)
			(layer "B.Fab")
			(hide yes)
			(effects
				(font
					(size 1 1)
					(thickness 0.15)
				)
				(justify mirror)
			)
		)
		(property "Val" "100n"
			(at 0 0 0)
			(layer "B.Fab")
			(hide yes)
			(effects
				(font
					(size 1 1)
					(thickness 0.15)
				)
				(justify mirror)
			)
		)
		(property "Voltage" "50V"
			(at 0 0 0)
			(layer "B.Fab")
			(hide yes)
			(effects
				(font
					(size 1 1)
					(thickness 0.15)
				)
				(justify mirror)
			)
		)
		(sheetname "HDMI")
		(sheetfile "hdmi.kicad_sch")
		(attr smd)
		(fp_rect
			(start -0.925 0.47)
			(end 0.925 -0.47)
			(stroke
				(width 0.05)
				(type default)
			)
			(fill none)
			(layer "B.CrtYd")
		)
		(fp_line
			(start -0.494 -0.248)
			(end 0.504 -0.248)
			(stroke
				(width 0.15)
				(type solid)
			)
			(layer "B.Fab")
		)
		(fp_line
			(start -0.494 0.25)
			(end -0.494 -0.248)
			(stroke
				(width 0.15)
				(type solid)
			)
			(layer "B.Fab")
		)
		(fp_line
			(start 0.504 -0.248)
			(end 0.504 0.25)
			(stroke
				(width 0.15)
				(type solid)
			)
			(layer "B.Fab")
		)
		(fp_line
			(start 0.504 0.25)
			(end -0.494 0.25)
			(stroke
				(width 0.15)
				(type solid)
			)
			(layer "B.Fab")
		)
		(fp_text user "Author: Antmicro"
			(at -0.932 -4.17 180)
			(layer "B.Fab")
			(hide yes)
			(effects
				(font
					(size 0.7 0.7)
					(thickness 0.15)
				)
				(justify left bottom mirror)
			)
		)
		(fp_text user "License: Apache-2.0"
			(at -0.932 -5.17 180)
			(layer "B.Fab")
			(hide yes)
			(effects
				(font
					(size 0.7 0.7)
					(thickness 0.15)
				)
				(justify left bottom mirror)
			)
		)
		(fp_text user "${REFERENCE}"
			(at -0.932 -3.168 180)
			(layer "B.Fab")
			(hide yes)
			(effects
				(font
					(size 0.7 0.7)
					(thickness 0.15)
				)
				(justify left bottom mirror)
			)
		)
		(pad "1" smd roundrect
			(at -0.48 0)
			(size 0.59 0.64)
			(layers "B.Cu" "B.Paste" "B.Mask")
			(roundrect_rratio 0.25)
			(net 699 "/HDMI/DP_MUX_D3-")
			(pintype "passive")
		)
		(pad "2" smd roundrect
			(at 0.48 0)
			(size 0.59 0.64)
			(layers "B.Cu" "B.Paste" "B.Mask")
			(roundrect_rratio 0.25)
			(net 274 "DP1_TXD0_HDMI_TX2_N")
			(pintype "passive")
		)
	)
	(footprint "antmicro-footprints:SOT-523"
		(layer "B.Cu")
		(at 48.7 74.3 180)
		(property "Reference" "Q22"
			(at -1.75 -1.85 180)
			(layer "B.SilkS")
			(effects
				(font
					(size 0.7 0.7)
					(thickness 0.15)
				)
				(justify left bottom mirror)
			)
		)
		(property "Value" "PJE138K"
			(at 0.1 -1.824 0)
			(layer "B.Fab")
			(effects
				(font
					(size 0.7 0.7)
					(thickness 0.15)
				)
				(justify left bottom mirror)
			)
		)
		(property "Footprint" "antmicro-footprints:SOT-523"
			(at 0 0 0)
			(layer "B.Fab")
			(hide yes)
			(effects
				(font
					(size 1.27 1.27)
					(thickness 0.15)
				)
				(justify mirror)
			)
		)
		(property "Datasheet" "https://www.mouser.com/datasheet/2/1057/PJE138K-1876698.pdf"
			(at 0 0 0)
			(layer "B.Fab")
			(hide yes)
			(effects
				(font
					(size 1.27 1.27)
					(thickness 0.15)
				)
				(justify mirror)
			)
		)
		(property "MPN" "PJE138K_R1_00001"
			(at 0 0 0)
			(unlocked yes)
			(layer "B.Fab")
			(hide yes)
			(effects
				(font
					(size 1 1)
					(thickness 0.15)
				)
				(justify mirror)
			)
		)
		(property "Manufacturer" "PANJIT"
			(at 0 0 0)
			(unlocked yes)
			(layer "B.Fab")
			(hide yes)
			(effects
				(font
					(size 1 1)
					(thickness 0.15)
				)
				(justify mirror)
			)
		)
		(property "Author" "Antmicro"
			(at 0 0 0)
			(unlocked yes)
			(layer "B.Fab")
			(hide yes)
			(effects
				(font
					(size 1 1)
					(thickness 0.15)
				)
				(justify mirror)
			)
		)
		(property "License" "Apache-2.0"
			(at 0 0 0)
			(unlocked yes)
			(layer "B.Fab")
			(hide yes)
			(effects
				(font
					(size 1 1)
					(thickness 0.15)
				)
				(justify mirror)
			)
		)
		(sheetname "Supply")
		(sheetfile "supply.kicad_sch")
		(attr smd)
		(fp_line
			(start -0.277 0.75)
			(end -0.277 0.551)
			(stroke
				(width 0.15)
				(type solid)
			)
			(layer "B.SilkS")
		)
		(fp_line
			(start -0.277 0.551)
			(end -0.725 0.551)
			(stroke
				(width 0.15)
				(type solid)
			)
			(layer "B.SilkS")
		)
		(fp_line
			(start -0.725 0.551)
			(end -0.927 0.351)
			(stroke
				(width 0.15)
				(type solid)
			)
			(layer "B.SilkS")
		)
		(fp_line
			(start -0.927 0.351)
			(end -0.927 0.051)
			(stroke
				(width 0.15)
				(type solid)
			)
			(layer "B.SilkS")
		)
		(fp_circle
			(center -0.9652 -0.9652)
			(end -0.9152 -0.9652)
			(stroke
				(width 0.15)
				(type solid)
			)
			(fill solid)
			(layer "B.SilkS")
		)
		(fp_line
			(start 1.1 1.16)
			(end -1.12 1.16)
			(stroke
				(width 0.05)
				(type solid)
			)
			(layer "B.CrtYd")
		)
		(fp_line
			(start 1.1 -1.15)
			(end 1.1 1.16)
			(stroke
				(width 0.05)
				(type solid)
			)
			(layer "B.CrtYd")
		)
		(fp_line
			(start 1.1 -1.15)
			(end -1.12 -1.15)
			(stroke
				(width 0.05)
				(type solid)
			)
			(layer "B.CrtYd")
		)
		(fp_line
			(start -1.12 -1.15)
			(end -1.12 1.16)
			(stroke
				(width 0.05)
				(type solid)
			)
			(layer "B.CrtYd")
		)
		(fp_line
			(start 0.8 -0.424)
			(end 0.8 0.425)
			(stroke
				(width 0.15)
				(type solid)
			)
			(layer "B.Fab")
		)
		(fp_line
			(start -0.652 0.425)
			(end 0.8 0.425)
			(stroke
				(width 0.15)
				(type solid)
			)
			(layer "B.Fab")
		)
		(fp_line
			(start -0.802 0.276)
			(end -0.652 0.425)
			(stroke
				(width 0.15)
				(type solid)
			)
			(layer "B.Fab")
		)
		(fp_line
			(start -0.802 -0.424)
			(end 0.8 -0.424)
			(stroke
				(width 0.15)
				(type solid)
			)
			(layer "B.Fab")
		)
		(fp_line
			(start -0.802 -0.424)
			(end -0.802 0.276)
			(stroke
				(width 0.15)
				(type solid)
			)
			(layer "B.Fab")
		)
		(fp_circle
			(center -0.9652 -0.9652)
			(end -0.9144 -0.9652)
			(stroke
				(width 0.15)
				(type solid)
			)
			(fill none)
			(layer "B.Fab")
		)
		(fp_text user "Author: Antmicro"
			(at -1.12 -6.224 0)
			(layer "B.Fab")
			(hide yes)
			(effects
				(font
					(size 0.7 0.7)
					(thickness 0.15)
				)
				(justify left bottom mirror)
			)
		)
		(fp_text user "${REFERENCE}"
			(at -1.12 -3.824 0)
			(layer "B.Fab")
			(hide yes)
			(effects
				(font
					(size 0.7 0.7)
					(thickness 0.15)
				)
				(justify left bottom mirror)
			)
		)
		(fp_text user "License: Apache-2.0"
			(at -1.12 -5.024 0)
			(layer "B.Fab")
			(hide yes)
			(effects
				(font
					(size 0.7 0.7)
					(thickness 0.15)
				)
				(justify left bottom mirror)
			)
		)
		(pad "1" smd rect
			(at -0.5 -0.65 180)
			(size 0.4 0.51)
			(layers "B.Cu" "B.Paste" "B.Mask")
			(net 799 "/Supply/PG_{HP}")
			(pinfunction "G")
			(pintype "passive")
		)
		(pad "2" smd rect
			(at 0.498 -0.65 180)
			(size 0.4 0.51)
			(layers "B.Cu" "B.Paste" "B.Mask")
			(net 1 "GND")
			(pinfunction "S")
			(pintype "passive")
		)
		(pad "3" smd rect
			(at 0 0.652 180)
			(size 0.4 0.51)
			(layers "B.Cu" "B.Paste" "B.Mask")
			(net 793 "Net-(D62-C)")
			(pinfunction "D")
			(pintype "passive")
		)
	)
	(footprint "antmicro-footprints:R_0402_1005Metric"
		(layer "B.Cu")
		(at 74 105.3 -90)
		(descr "Resistor SMD 0402")
		(tags "resistor SMD 0402")
		(property "Reference" "R86"
			(at -5.03 -1.69 90)
			(layer "B.SilkS")
			(effects
				(font
					(size 0.7 0.7)
					(thickness 0.15)
				)
				(justify left bottom mirror)
			)
		)
		(property "Value" "R_1k_0402"
			(at 0 -1.4 90)
			(layer "B.Fab")
			(effects
				(font
					(size 0.7 0.7)
					(thickness 0.15)
				)
				(justify left bottom mirror)
			)
		)
		(property "Footprint" "antmicro-footprints:R_0402_1005Metric"
			(at 0 0 -90)
			(layer "F.Fab")
			(hide yes)
			(effects
				(font
					(size 1.27 1.27)
					(thickness 0.15)
				)
			)
		)
		(property "Datasheet" "https://www.bourns.com/docs/product-datasheets/cr.pdf"
			(at 0 0 -90)
			(layer "F.Fab")
			(hide yes)
			(effects
				(font
					(size 1.27 1.27)
					(thickness 0.15)
				)
			)
		)
		(property "Author" "Antmicro"
			(at -31.3 179.3 0)
			(layer "B.Fab")
			(hide yes)
			(effects
				(font
					(size 1 1)
					(thickness 0.15)
				)
				(justify mirror)
			)
		)
		(property "License" "Apache-2.0"
			(at -31.3 179.3 0)
			(layer "B.Fab")
			(hide yes)
			(effects
				(font
					(size 1 1)
					(thickness 0.15)
				)
				(justify mirror)
			)
		)
		(property "MPN" "CR0402-FX-1001GLF"
			(at -31.3 179.3 0)
			(layer "B.Fab")
			(hide yes)
			(effects
				(font
					(size 1 1)
					(thickness 0.15)
				)
				(justify mirror)
			)
		)
		(property "Manufacturer" "Bourns"
			(at -31.3 179.3 0)
			(layer "B.Fab")
			(hide yes)
			(effects
				(font
					(size 1 1)
					(thickness 0.15)
				)
				(justify mirror)
			)
		)
		(property "Tolerance" "1%"
			(at -31.3 179.3 0)
			(layer "B.Fab")
			(hide yes)
			(effects
				(font
					(size 1 1)
					(thickness 0.15)
				)
				(justify mirror)
			)
		)
		(property "Val" "1k"
			(at -31.3 179.3 0)
			(layer "B.Fab")
			(hide yes)
			(effects
				(font
					(size 1 1)
					(thickness 0.15)
				)
				(justify mirror)
			)
		)
		(sheetname "USB Debug, DP")
		(sheetfile "usb.kicad_sch")
		(attr smd)
		(fp_rect
			(start -0.925 0.47)
			(end 0.925 -0.47)
			(stroke
				(width 0.05)
				(type default)
			)
			(fill none)
			(layer "B.CrtYd")
		)
		(fp_rect
			(start -0.5 0.25)
			(end 0.5 -0.25)
			(stroke
				(width 0.15)
				(type solid)
			)
			(fill none)
			(layer "B.Fab")
		)
		(fp_text user "${REFERENCE}"
			(at -0.95 -3.168 90)
			(layer "B.Fab")
			(hide yes)
			(effects
				(font
					(size 0.7 0.7)
					(thickness 0.15)
				)
				(justify left bottom mirror)
			)
		)
		(fp_text user "Author: Antmicro"
			(at -0.95 -4.169 90)
			(layer "B.Fab")
			(hide yes)
			(effects
				(font
					(size 0.7 0.7)
					(thickness 0.15)
				)
				(justify left bottom mirror)
			)
		)
		(fp_text user "License: Apache-2.0"
			(at -0.95 -5.169 90)
			(layer "B.Fab")
			(hide yes)
			(effects
				(font
					(size 0.7 0.7)
					(thickness 0.15)
				)
				(justify left bottom mirror)
			)
		)
		(pad "1" smd roundrect
			(at -0.48 0 270)
			(size 0.59 0.64)
			(layers "B.Cu" "B.Paste" "B.Mask")
			(roundrect_rratio 0.25)
			(net 304 "/USB Debug, DP/USBC0_I2C_EN")
			(pintype "passive")
		)
		(pad "2" smd roundrect
			(at 0.48 0 270)
			(size 0.59 0.64)
			(layers "B.Cu" "B.Paste" "B.Mask")
			(roundrect_rratio 0.25)
			(net 1 "GND")
			(pintype "passive")
		)
	)
)
